# T6G (Grand Teton) — schematic netlist excerpt (pin names and nets, part order shuffled) for the footprints in the layout excerpt that follows; sources: Cadence DE-HDL packaged netlist, KiCad conversion of 04192023_DAF0TMB3IC0_F0TG_MB_C_brd_V02_OCP.brd

C2450  Q_CAP  22UF 4V 20% X6S  pkg C0402  page 74 : A = PVDDCR_SOC_P1 ; B = GND
R1273  Q_RES  0 5% CHIP  pkg 0402LF  page 357 : A = SMB_INA230_6_3V3AUX_SCL_R ; B = SMB_INA230_6_3V3AUX_SCL_R1
C6643  Q_CAP_DIFFBUS  DIFF BUS_0.22UF 6.3V 20% X6S  pkg C0201  page 319 : \1\ = P5E_CPU1_P0_TX_BUF_C_DP<7> ; \2\ = P5E_CPU1_P0_TX_BUF_DP<7>

(kicad_pcb
	(version 20260206)
	(generator "pcbnew")
	(generator_version "10.0")
	(general
		(thickness 1.6)
		(legacy_teardrops no)
	)
	(paper "A4")
	(title_block
		(title "04192023_DAF0TMB3IC0_F0TG_MB_C_brd_V02_OCP.brd")
		(comment 1 "Grand Teton / footprints 3031-3033 of 8354")
	)
	(layers
		(0 "F.Cu" signal "TOP")
		(4 "In1.Cu" signal "GND")
		(6 "In2.Cu" signal "IN1")
		(8 "In3.Cu" signal "GND1")
		(10 "In4.Cu" signal "IN2")
		(12 "In5.Cu" signal "GND2")
		(14 "In6.Cu" signal "IN3")
		(16 "In7.Cu" signal "GND3")
		(18 "In8.Cu" signal "VCC")
		(20 "In9.Cu" signal "VCC1")
		(22 "In10.Cu" signal "GND4")
		(24 "In11.Cu" signal "IN4")
		(26 "In12.Cu" signal "GND5")
		(28 "In13.Cu" signal "IN5")
		(30 "In14.Cu" signal "GND6")
		(32 "In15.Cu" signal "IN6")
		(34 "In16.Cu" signal "GND7")
		(2 "B.Cu" signal "BOTTOM")
		(9 "F.Adhes" user "F.Adhesive")
		(11 "B.Adhes" user "B.Adhesive")
		(13 "F.Paste" user "Package Geometry/Pastemask Top")
		(15 "B.Paste" user "Package Geometry/Pastemask Bottom")
		(5 "F.SilkS" user "Ref Des/Silkscreen Top")
		(7 "B.SilkS" user "Ref Des/Silkscreen Bottom")
		(1 "F.Mask" user "Board Geometry/Soldermask Top")
		(3 "B.Mask" user "Board Geometry/Soldermask Bottom")
		(17 "Dwgs.User" user "User.Drawings")
		(19 "Cmts.User" user "User.Comments")
		(21 "Eco1.User" user "User.Eco1")
		(23 "Eco2.User" user "User.Eco2")
		(25 "Edge.Cuts" user "Board Geometry/Outline")
		(27 "Margin" user)
		(31 "F.CrtYd" user "Package Geometry/Place Bound Top")
		(29 "B.CrtYd" user "Package Geometry/Place Bound Bottom")
		(35 "F.Fab" user "Ref Des/Assembly Top")
		(33 "B.Fab" user "Ref Des/Assembly Bottom")
	)
	(footprint ""
		(layer "F.Cu")
		(at 395.037056 -72.28205 180)
		(property "Reference" "R1273"
			(at 0 0 180)
			(layer "F.SilkS")
			(hide yes)
			(effects
				(font
					(size 1.27 1.27)
				)
			)
		)
		(property "Value" ""
			(at 0 0 180)
			(layer "F.Fab")
			(effects
				(font
					(size 1.27 1.27)
				)
			)
		)
		(duplicate_pad_numbers_are_jumpers no)
		(fp_line
			(start 0.7874 0.4064)
			(end -0.7874 0.4064)
			(stroke
				(width 0.1524)
				(type default)
			)
			(layer "F.SilkS")
		)
		(fp_line
			(start 0.7874 -0.4064)
			(end 0.7874 0.4064)
			(stroke
				(width 0.1524)
				(type default)
			)
			(layer "F.SilkS")
		)
		(fp_line
			(start -0.7874 0.4064)
			(end -0.7874 -0.4064)
			(stroke
				(width 0.1524)
				(type default)
			)
			(layer "F.SilkS")
		)
		(fp_line
			(start -0.7874 -0.4064)
			(end 0.7874 -0.4064)
			(stroke
				(width 0.1524)
				(type default)
			)
			(layer "F.SilkS")
		)
		(fp_line
			(start 0.67945 0.3048)
			(end 0.120396 0.3048)
			(stroke
				(width 0.1)
				(type default)
			)
			(layer "F.Fab")
		)
		(fp_line
			(start 0.67945 -0.3048)
			(end 0.67945 0.3048)
			(stroke
				(width 0.1)
				(type default)
			)
			(layer "F.Fab")
		)
		(fp_line
			(start 0.12065 -0.2794)
			(end 0.12065 -0.3048)
			(stroke
				(width 0.1)
				(type default)
			)
			(layer "F.Fab")
		)
		(fp_line
			(start 0.12065 -0.3048)
			(end 0.67945 -0.3048)
			(stroke
				(width 0.1)
				(type default)
			)
			(layer "F.Fab")
		)
		(fp_line
			(start 0.120396 0.3048)
			(end 0.120396 0.2794)
			(stroke
				(width 0.1)
				(type default)
			)
			(layer "F.Fab")
		)
		(fp_line
			(start 0.120396 0.2794)
			(end -0.12065 0.2794)
			(stroke
				(width 0.1)
				(type default)
			)
			(layer "F.Fab")
		)
		(fp_line
			(start -0.12065 0.3048)
			(end -0.67945 0.3048)
			(stroke
				(width 0.1)
				(type default)
			)
			(layer "F.Fab")
		)
		(fp_line
			(start -0.12065 0.2794)
			(end -0.12065 0.3048)
			(stroke
				(width 0.1)
				(type default)
			)
			(layer "F.Fab")
		)
		(fp_line
			(start -0.12065 -0.2794)
			(end 0.12065 -0.2794)
			(stroke
				(width 0.1)
				(type default)
			)
			(layer "F.Fab")
		)
		(fp_line
			(start -0.12065 -0.305054)
			(end -0.12065 -0.2794)
			(stroke
				(width 0.1)
				(type default)
			)
			(layer "F.Fab")
		)
		(fp_line
			(start -0.67945 0.3048)
			(end -0.67945 -0.305054)
			(stroke
				(width 0.1)
				(type default)
			)
			(layer "F.Fab")
		)
		(fp_line
			(start -0.67945 -0.305054)
			(end -0.12065 -0.305054)
			(stroke
				(width 0.1)
				(type default)
			)
			(layer "F.Fab")
		)
		(pad "1" smd circle
			(at -0.40005 0 180)
			(size 0 0)
			(layers "F.Cu" "F.Mask" "F.Paste")
			(net "SMB_INA230_6_3V3AUX_SCL_R")
		)
		(pad "2" smd circle
			(at 0.40005 0 180)
			(size 0 0)
			(layers "F.Cu" "F.Mask" "F.Paste")
			(net "SMB_INA230_6_3V3AUX_SCL_R1")
		)
	)
	(footprint ""
		(layer "F.Cu")
		(at 113.105946 -257.74523)
		(property "Reference" "C2450"
			(at 0 0 0)
			(layer "F.SilkS")
			(hide yes)
			(effects
				(font
					(size 1.27 1.27)
				)
			)
		)
		(property "Value" ""
			(at 0 0 0)
			(layer "F.Fab")
			(effects
				(font
					(size 1.27 1.27)
				)
			)
		)
		(duplicate_pad_numbers_are_jumpers no)
		(fp_line
			(start -0.7874 -0.4064)
			(end 0.7874 -0.4064)
			(stroke
				(width 0.1524)
				(type default)
			)
			(layer "F.SilkS")
		)
		(fp_line
			(start -0.7874 0.4064)
			(end -0.7874 -0.4064)
			(stroke
				(width 0.1524)
				(type default)
			)
			(layer "F.SilkS")
		)
		(fp_line
			(start 0.7874 -0.4064)
			(end 0.7874 0.4064)
			(stroke
				(width 0.1524)
				(type default)
			)
			(layer "F.SilkS")
		)
		(fp_line
			(start 0.7874 0.4064)
			(end -0.7874 0.4064)
			(stroke
				(width 0.1524)
				(type default)
			)
			(layer "F.SilkS")
		)
		(fp_line
			(start -0.67945 -0.305054)
			(end -0.12065 -0.305054)
			(stroke
				(width 0.1)
				(type default)
			)
			(layer "F.Fab")
		)
		(fp_line
			(start -0.67945 0.3048)
			(end -0.67945 -0.305054)
			(stroke
				(width 0.1)
				(type default)
			)
			(layer "F.Fab")
		)
		(fp_line
			(start -0.12065 -0.305054)
			(end -0.12065 -0.2794)
			(stroke
				(width 0.1)
				(type default)
			)
			(layer "F.Fab")
		)
		(fp_line
			(start -0.12065 -0.2794)
			(end 0.12065 -0.2794)
			(stroke
				(width 0.1)
				(type default)
			)
			(layer "F.Fab")
		)
		(fp_line
			(start -0.12065 0.2794)
			(end -0.12065 0.3048)
			(stroke
				(width 0.1)
				(type default)
			)
			(layer "F.Fab")
		)
		(fp_line
			(start -0.12065 0.3048)
			(end -0.67945 0.3048)
			(stroke
				(width 0.1)
				(type default)
			)
			(layer "F.Fab")
		)
		(fp_line
			(start 0.120396 0.2794)
			(end -0.12065 0.2794)
			(stroke
				(width 0.1)
				(type default)
			)
			(layer "F.Fab")
		)
		(fp_line
			(start 0.120396 0.3048)
			(end 0.120396 0.2794)
			(stroke
				(width 0.1)
				(type default)
			)
			(layer "F.Fab")
		)
		(fp_line
			(start 0.12065 -0.3048)
			(end 0.67945 -0.3048)
			(stroke
				(width 0.1)
				(type default)
			)
			(layer "F.Fab")
		)
		(fp_line
			(start 0.12065 -0.2794)
			(end 0.12065 -0.3048)
			(stroke
				(width 0.1)
				(type default)
			)
			(layer "F.Fab")
		)
		(fp_line
			(start 0.67945 -0.3048)
			(end 0.67945 0.3048)
			(stroke
				(width 0.1)
				(type default)
			)
			(layer "F.Fab")
		)
		(fp_line
			(start 0.67945 0.3048)
			(end 0.120396 0.3048)
			(stroke
				(width 0.1)
				(type default)
			)
			(layer "F.Fab")
		)
		(pad "1" smd circle
			(at -0.40005 0)
			(size 0 0)
			(layers "F.Cu" "F.Mask" "F.Paste")
			(net "PVDDCR_SOC_P1")
		)
		(pad "2" smd circle
			(at 0.40005 0)
			(size 0 0)
			(layers "F.Cu" "F.Mask" "F.Paste")
			(net "GND")
		)
	)
	(footprint ""
		(layer "F.Cu")
		(at 70.125844 -408.517344 -90)
		(property "Reference" "C6643"
			(at 0 0 270)
			(layer "F.SilkS")
			(hide yes)
			(effects
				(font
					(size 1.27 1.27)
				)
			)
		)
		(property "Value" ""
			(at 0 0 270)
			(layer "F.Fab")
			(effects
				(font
					(size 1.27 1.27)
				)
			)
		)
		(duplicate_pad_numbers_are_jumpers no)
		(fp_line
			(start -0.299974 0.150114)
			(end -0.299974 -0.150114)
			(stroke
				(width 0.1)
				(type default)
			)
			(layer "F.Fab")
		)
		(fp_line
			(start 0.299974 0.150114)
			(end -0.299974 0.150114)
			(stroke
				(width 0.1)
				(type default)
			)
			(layer "F.Fab")
		)
		(fp_line
			(start -0.299974 -0.150114)
			(end 0.299974 -0.150114)
			(stroke
				(width 0.1)
				(type default)
			)
			(layer "F.Fab")
		)
		(fp_line
			(start 0.299974 -0.150114)
			(end 0.299974 0.150114)
			(stroke
				(width 0.1)
				(type default)
			)
			(layer "F.Fab")
		)
		(pad "1" smd rect
			(at -0.2667 0 270)
			(size 0.3048 0.381)
			(layers "F.Cu" "F.Mask" "F.Paste")
			(net "P5E_CPU1_P0_TX_BUF_C_DP<7>")
		)
		(pad "2" smd rect
			(at 0.2667 0 270)
			(size 0.3048 0.381)
			(layers "F.Cu" "F.Mask" "F.Paste")
			(net "P5E_CPU1_P0_TX_BUF_DP<7>")
		)
	)
)
